(kicad_pcb
	(version 20221018)
	(generator pcbnew)
	(general
    (thickness 1.562)
  )
	(paper "A4")
	(title_block
    (title "Thunderbolt PCIe Adaper")
    (date "2024-07-09")
    (rev "1.0.3")
    (comment 1 "www.antmicro.com")
    (comment 2 "Antmicro Ltd.")
		(comment 9 "footprints 72-79 of 271")
	)
	(layers
    (0 "F.Cu" signal)
    (1 "In1.Cu" signal)
    (2 "In2.Cu" signal)
    (3 "In3.Cu" signal)
    (4 "In4.Cu" signal)
    (31 "B.Cu" signal)
    (32 "B.Adhes" user "B.Adhesive")
    (33 "F.Adhes" user "F.Adhesive")
    (34 "B.Paste" user)
    (35 "F.Paste" user)
    (36 "B.SilkS" user "B.Silkscreen")
    (37 "F.SilkS" user "F.Silkscreen")
    (38 "B.Mask" user)
    (39 "F.Mask" user)
    (40 "Dwgs.User" user "User.Drawings")
    (41 "Cmts.User" user "User.Comments")
    (42 "Eco1.User" user "User.Eco1")
    (43 "Eco2.User" user "User.Eco2")
    (44 "Edge.Cuts" user)
    (45 "Margin" user)
    (46 "B.CrtYd" user "B.Courtyard")
    (47 "F.CrtYd" user "F.Courtyard")
    (48 "B.Fab" user)
    (49 "F.Fab" user)
  )
	(footprint "antmicro-footprints:SOT-363" (layer "F.Cu")
    (at 106.9475 91.3 90)
    (property "Author" "Antmicro")
    (property "License" "Apache-2.0")
    (property "MPN" "DZDH0401DW")
    (property "Manufacturer" "Diodes Incorporated")
    (property "Sheetfile" "power.kicad_sch")
    (property "Sheetname" "Power")
    (property "ki_description" "OR Controller N+1 ORing Controller P-Channel 1:1 SOT-363")
    (property "ki_keywords" "SMT, CONTROLLER, SEMICONDUCTOR, DIODE, PMOS")
    (attr smd)
    (fp_text reference "Q3" (at -0.775 -1.5 90) (layer "F.SilkS")
        (effects (font (size 0.7 0.7) (thickness 0.15)) (justify left bottom))
    )
    (fp_text value "DZDH0401DW" (at 0 2.2 90) (layer "F.Fab")
        (effects (font (size 0.7 0.7) (thickness 0.15)) (justify left bottom))
    )
    (fp_text user "${REFERENCE}" (at -1.3 4 90) (layer "F.Fab") hide
        (effects (font (size 0.7 0.7) (thickness 0.15)) (justify left bottom))
    )
    (fp_text user "Author: Antmicro" (at -1.3 6.4 90) (layer "F.Fab") hide
        (effects (font (size 0.7 0.7) (thickness 0.15)) (justify left bottom))
    )
    (fp_text user "License: Apache-2.0" (at -1.3 5.2 90) (layer "F.Fab") hide
        (effects (font (size 0.7 0.7) (thickness 0.15)) (justify left bottom))
    )
    (fp_line (start -0.8 1.146) (end -0.8 1.223)
      (stroke (width 0.15) (type solid)) (layer "F.SilkS"))
    (fp_line (start -0.8 1.223) (end 0.803 1.223)
      (stroke (width 0.15) (type solid)) (layer "F.SilkS"))
    (fp_line (start -0.72 -1.153) (end -0.72 -1.228)
      (stroke (width 0.15) (type solid)) (layer "F.SilkS"))
    (fp_line (start 0.803 -1.228) (end -0.72 -1.228)
      (stroke (width 0.15) (type solid)) (layer "F.SilkS"))
    (fp_line (start 0.803 -1.153) (end 0.803 -1.228)
      (stroke (width 0.15) (type solid)) (layer "F.SilkS"))
    (fp_line (start 0.803 1.146) (end 0.803 1.223)
      (stroke (width 0.15) (type solid)) (layer "F.SilkS"))
    (fp_circle (center -0.978102 -1.2) (end -0.928102 -1.2)
      (stroke (width 0.15) (type solid)) (fill solid) (layer "F.SilkS"))
    (fp_rect (start 1.3 -1.3) (end -1.3 1.3)
      (stroke (width 0.05) (type solid)) (fill none) (layer "F.CrtYd"))
    (fp_line (start -0.1 -1.1) (end -0.68 -0.52)
      (stroke (width 0.15) (type solid)) (layer "F.Fab"))
    (fp_rect (start 0.68 1.1) (end -0.68 -1.1)
      (stroke (width 0.15) (type solid)) (fill none) (layer "F.Fab"))
    (pad "1" smd custom (at -0.948 -0.752) (size 0.6 0.6) (layers "F.Cu" "F.Paste" "F.Mask")
      (options (clearance outline) (anchor rect))
      (primitives
      ))
    (pad "2" smd rect (at -0.948 -0.002) (size 0.4 0.6) (layers "F.Cu" "F.Paste" "F.Mask")
      (net 141 "Net-(Q3-REF)") (pinfunction "REF") (pintype "input"))
    (pad "3" smd custom (at -0.948 0.745) (size 0.6 0.6) (layers "F.Cu" "F.Paste" "F.Mask")
      (net 142 "Net-(Q3-BIAS)") (pinfunction "BIAS") (pintype "output")
      (options (clearance outline) (anchor rect))
      (primitives
      ))
    (pad "4" smd custom (at 0.951 0.745) (size 0.6 0.6) (layers "F.Cu" "F.Paste" "F.Mask")
      (net 143 "Net-(Q3-S)") (pinfunction "S") (pintype "power_in")
      (options (clearance outline) (anchor rect))
      (primitives
      ))
    (pad "5" smd rect (at 0.951 -0.002) (size 0.4 0.6) (layers "F.Cu" "F.Paste" "F.Mask"))
    (pad "6" smd custom (at 0.951 -0.752) (size 0.6 0.6) (layers "F.Cu" "F.Paste" "F.Mask")
      (net 61 "12V0_MOLEX") (pinfunction "D") (pintype "power_in")
      (options (clearance outline) (anchor rect))
      (primitives
      ))
  )
	(footprint "antmicro-footprints:C_0402_1005Metric" (layer "B.Cu")
    (at 144.15 76.432 90)
    (descr "Capacitor SMD 0402")
    (tags "capacitor SMD 0402")
    (property "Author" "Antmicro")
    (property "Dielectric" "")
    (property "License" "Apache-2.0")
    (property "MPN" "CC0402MRX5R5BB106")
    (property "Manufacturer" "YAGEO")
    (property "Sheetfile" "tb-power.kicad_sch")
    (property "Sheetname" "Thunderbolt Controller - Power")
    (property "Val" "10u")
    (property "Voltage" "")
    (property "ki_description" "SMD Multilayer Ceramic Capacitor, 10 µF, 6.3 V, 0402 [1005 Metric], ± 20%, X5R, CC Series")
    (property "ki_keywords" "0402, SMT, CAPACITOR, PASSIVE, MLCC, CERAMIC")
    (attr smd)
    (fp_text reference "C83" (at 5.439 1.519 270) (layer "B.SilkS")
        (effects (font (size 0.7 0.7) (thickness 0.15)) (justify left bottom mirror))
    )
    (fp_text value "C_10u_0402" (at -1.022927 -2.155213 270) (layer "B.Fab")
        (effects (font (size 0.7 0.7) (thickness 0.15)) (justify left bottom mirror))
    )
    (fp_text user "License: Apache-2.0" (at -0.939 -5.799 270) (layer "B.Fab") hide
        (effects (font (size 0.7 0.7) (thickness 0.15)) (justify left bottom mirror))
    )
    (fp_text user "Author: Antmicro" (at -0.939 -3.399 270) (layer "B.Fab") hide
        (effects (font (size 0.7 0.7) (thickness 0.15)) (justify left bottom mirror))
    )
    (fp_text user "${REFERENCE}" (at -0.939 -4.599 270) (layer "B.Fab") hide
        (effects (font (size 0.7 0.7) (thickness 0.15)) (justify left bottom mirror))
    )
    (fp_rect (start -0.925 0.47) (end 0.925 -0.47)
      (stroke (width 0.05) (type default)) (fill none) (layer "B.CrtYd"))
    (fp_line (start -0.494 -0.248) (end -0.494 0.25)
      (stroke (width 0.15) (type solid)) (layer "B.Fab"))
    (fp_line (start -0.494 0.25) (end 0.504 0.25)
      (stroke (width 0.15) (type solid)) (layer "B.Fab"))
    (fp_line (start 0.504 -0.248) (end -0.494 -0.248)
      (stroke (width 0.15) (type solid)) (layer "B.Fab"))
    (fp_line (start 0.504 0.25) (end 0.504 -0.248)
      (stroke (width 0.15) (type solid)) (layer "B.Fab"))
    (pad "1" smd roundrect (at -0.48 0 90) (size 0.59 0.64) (layers "B.Cu" "B.Paste" "B.Mask") (roundrect_rratio 0.25)
      (net 1 "GND") (pintype "passive"))
    (pad "2" smd roundrect (at 0.48 0 90) (size 0.59 0.64) (layers "B.Cu" "B.Paste" "B.Mask") (roundrect_rratio 0.25)
      (net 2 "3V3_SYS") (pintype "passive"))
  )
	(footprint "antmicro-footprints:R_0402_1005Metric" (layer "B.Cu")
    (at 107.85 91.765 -90)
    (descr "Resistor SMD 0402")
    (tags "resistor SMD 0402")
    (property "Author" "Antmicro")
    (property "License" "Apache-2.0")
    (property "MPN" "CR0402-FX-1003GLF")
    (property "Manufacturer" "Bourns")
    (property "Sheetfile" "power.kicad_sch")
    (property "Sheetname" "Power")
    (property "Tolerance" "1%")
    (property "Val" "100k")
    (property "ki_description" "SMD Chip Resistor, 100 kohm, ± 1%, 62.5 mW, 0402 [1005 Metric], Thick Film, General Purpose")
    (property "ki_keywords" "0402, SMT, RESISTOR, PASSIVE")
    (attr smd)
    (fp_text reference "R95" (at -1.087 -1.497 90) (layer "B.SilkS")
        (effects (font (size 0.7 0.7) (thickness 0.15)) (justify left bottom mirror))
    )
    (fp_text value "R_100k_0402" (at -1.011843 -1.772047 90) (layer "B.Fab")
        (effects (font (size 0.7 0.7) (thickness 0.15)) (justify left bottom mirror))
    )
    (fp_text user "${REFERENCE}" (at -0.95 -3.168 90) (layer "B.Fab") hide
        (effects (font (size 0.7 0.7) (thickness 0.15)) (justify left bottom mirror))
    )
    (fp_text user "License: Apache-2.0" (at -0.95 -5.169 90) (layer "B.Fab") hide
        (effects (font (size 0.7 0.7) (thickness 0.15)) (justify left bottom mirror))
    )
    (fp_text user "Author: Antmicro" (at -0.95 -4.169 90) (layer "B.Fab") hide
        (effects (font (size 0.7 0.7) (thickness 0.15)) (justify left bottom mirror))
    )
    (fp_rect (start -0.925 0.47) (end 0.925 -0.47)
      (stroke (width 0.05) (type default)) (fill none) (layer "B.CrtYd"))
    (fp_rect (start -0.5 0.25) (end 0.5 -0.25)
      (stroke (width 0.15) (type solid)) (fill none) (layer "B.Fab"))
    (pad "1" smd roundrect (at -0.48 0 270) (size 0.59 0.64) (layers "B.Cu" "B.Paste" "B.Mask") (roundrect_rratio 0.25)
      (net 1 "GND") (pintype "passive"))
    (pad "2" smd roundrect (at 0.48 0 270) (size 0.59 0.64) (layers "B.Cu" "B.Paste" "B.Mask") (roundrect_rratio 0.25)
      (net 142 "Net-(Q3-BIAS)") (pintype "passive"))
  )
	(footprint "antmicro-footprints:R_0402_1005Metric" (layer "B.Cu")
    (at 138.25 70.72 90)
    (descr "Resistor SMD 0402")
    (tags "resistor SMD 0402")
    (property "Author" "Antmicro")
    (property "License" "Apache-2.0")
    (property "MPN" "CR0402-FX-1003GLF")
    (property "Manufacturer" "Bourns")
    (property "Sheetfile" "tb.kicad_sch")
    (property "Sheetname" "TB Controller")
    (property "Tolerance" "1%")
    (property "Val" "100k")
    (property "ki_description" "SMD Chip Resistor, 100 kohm, ± 1%, 62.5 mW, 0402 [1005 Metric], Thick Film, General Purpose")
    (property "ki_keywords" "0402, SMT, RESISTOR, PASSIVE")
    (attr smd)
    (fp_text reference "R86" (at -1.035 0.434 270) (layer "B.SilkS")
        (effects (font (size 0.7 0.7) (thickness 0.15)) (justify left bottom mirror))
    )
    (fp_text value "R_100k_0402" (at -1.011843 -1.772047 270) (layer "B.Fab")
        (effects (font (size 0.7 0.7) (thickness 0.15)) (justify left bottom mirror))
    )
    (fp_text user "Author: Antmicro" (at -0.95 -4.169 270) (layer "B.Fab") hide
        (effects (font (size 0.7 0.7) (thickness 0.15)) (justify left bottom mirror))
    )
    (fp_text user "${REFERENCE}" (at -0.95 -3.168 270) (layer "B.Fab") hide
        (effects (font (size 0.7 0.7) (thickness 0.15)) (justify left bottom mirror))
    )
    (fp_text user "License: Apache-2.0" (at -0.95 -5.169 270) (layer "B.Fab") hide
        (effects (font (size 0.7 0.7) (thickness 0.15)) (justify left bottom mirror))
    )
    (fp_rect (start -0.925 0.47) (end 0.925 -0.47)
      (stroke (width 0.05) (type default)) (fill none) (layer "B.CrtYd"))
    (fp_rect (start -0.5 0.25) (end 0.5 -0.25)
      (stroke (width 0.15) (type solid)) (fill none) (layer "B.Fab"))
    (pad "1" smd roundrect (at -0.48 0 90) (size 0.59 0.64) (layers "B.Cu" "B.Paste" "B.Mask") (roundrect_rratio 0.25)
      (net 201 "Net-(U4C-POC_GPIO_5)") (pintype "passive"))
    (pad "2" smd roundrect (at 0.48 0 90) (size 0.59 0.64) (layers "B.Cu" "B.Paste" "B.Mask") (roundrect_rratio 0.25)
      (net 1 "GND") (pintype "passive"))
  )
	(footprint "antmicro-footprints:R_0402_1005Metric" (layer "B.Cu")
    (at 106.9455 89.2 180)
    (descr "Resistor SMD 0402")
    (tags "resistor SMD 0402")
    (property "Author" "Antmicro")
    (property "License" "Apache-2.0")
    (property "MPN" "CR0402-FX-2201GLF")
    (property "Manufacturer" "Bourns")
    (property "Sheetfile" "power.kicad_sch")
    (property "Sheetname" "Power")
    (property "Tolerance" "1%")
    (property "Val" "2k2")
    (property "ki_description" "SMD Chip Resistor, 2.2 kohm, ± 1%, 62.5 mW, 0402 [1005 Metric], Thick Film, General Purpose")
    (property "ki_keywords" "0402, SMT, RESISTOR, PASSIVE")
    (attr smd)
    (fp_text reference "R97" (at -1.122484 0.772697) (layer "B.SilkS")
        (effects (font (size 0.7 0.7) (thickness 0.15)) (justify left bottom mirror))
    )
    (fp_text value "R_2k2_0402" (at -1.011843 -1.772047) (layer "B.Fab")
        (effects (font (size 0.7 0.7) (thickness 0.15)) (justify left bottom mirror))
    )
    (fp_text user "Author: Antmicro" (at -0.95 -4.169) (layer "B.Fab") hide
        (effects (font (size 0.7 0.7) (thickness 0.15)) (justify left bottom mirror))
    )
    (fp_text user "${REFERENCE}" (at -0.95 -3.168) (layer "B.Fab") hide
        (effects (font (size 0.7 0.7) (thickness 0.15)) (justify left bottom mirror))
    )
    (fp_text user "License: Apache-2.0" (at -0.95 -5.169) (layer "B.Fab") hide
        (effects (font (size 0.7 0.7) (thickness 0.15)) (justify left bottom mirror))
    )
    (fp_rect (start -0.925 0.47) (end 0.925 -0.47)
      (stroke (width 0.05) (type default)) (fill none) (layer "B.CrtYd"))
    (fp_rect (start -0.5 0.25) (end 0.5 -0.25)
      (stroke (width 0.15) (type solid)) (fill none) (layer "B.Fab"))
    (pad "1" smd roundrect (at -0.48 0 180) (size 0.59 0.64) (layers "B.Cu" "B.Paste" "B.Mask") (roundrect_rratio 0.25)
      (net 1 "GND") (pintype "passive"))
    (pad "2" smd roundrect (at 0.48 0 180) (size 0.59 0.64) (layers "B.Cu" "B.Paste" "B.Mask") (roundrect_rratio 0.25)
      (net 123 "Net-(D5-C)") (pintype "passive"))
  )
	(footprint "antmicro-footprints:R_0402_1005Metric" (layer "B.Cu")
    (at 151.41 63.97 180)
    (descr "Resistor SMD 0402")
    (tags "resistor SMD 0402")
    (property "Author" "Antmicro")
    (property "License" "Apache-2.0")
    (property "MPN" "CR0402-FX-1003GLF")
    (property "Manufacturer" "Bourns")
    (property "Sheetfile" "power.kicad_sch")
    (property "Sheetname" "Power")
    (property "Tolerance" "1%")
    (property "Val" "100k")
    (property "ki_description" "SMD Chip Resistor, 100 kohm, ± 1%, 62.5 mW, 0402 [1005 Metric], Thick Film, General Purpose")
    (property "ki_keywords" "0402, SMT, RESISTOR, PASSIVE")
    (attr smd)
    (fp_text reference "R9" (at 0.961516 -0.382303) (layer "B.SilkS")
        (effects (font (size 0.7 0.7) (thickness 0.15)) (justify left bottom mirror))
    )
    (fp_text value "R_100k_0402" (at -1.011843 -1.772047) (layer "B.Fab")
        (effects (font (size 0.7 0.7) (thickness 0.15)) (justify left bottom mirror))
    )
    (fp_text user "License: Apache-2.0" (at -0.95 -5.169) (layer "B.Fab") hide
        (effects (font (size 0.7 0.7) (thickness 0.15)) (justify left bottom mirror))
    )
    (fp_text user "Author: Antmicro" (at -0.95 -4.169) (layer "B.Fab") hide
        (effects (font (size 0.7 0.7) (thickness 0.15)) (justify left bottom mirror))
    )
    (fp_text user "${REFERENCE}" (at -0.95 -3.168) (layer "B.Fab") hide
        (effects (font (size 0.7 0.7) (thickness 0.15)) (justify left bottom mirror))
    )
    (fp_rect (start -0.925 0.47) (end 0.925 -0.47)
      (stroke (width 0.05) (type default)) (fill none) (layer "B.CrtYd"))
    (fp_rect (start -0.5 0.25) (end 0.5 -0.25)
      (stroke (width 0.15) (type solid)) (fill none) (layer "B.Fab"))
    (pad "1" smd roundrect (at -0.48 0 180) (size 0.59 0.64) (layers "B.Cu" "B.Paste" "B.Mask") (roundrect_rratio 0.25)
      (net 1 "GND") (pintype "passive"))
    (pad "2" smd roundrect (at 0.48 0 180) (size 0.59 0.64) (layers "B.Cu" "B.Paste" "B.Mask") (roundrect_rratio 0.25)
      (net 16 "AUX_P") (pintype "passive"))
  )
	(footprint "antmicro-footprints:R_0402_1005Metric" (layer "B.Cu")
    (at 130.7 83.12)
    (descr "Resistor SMD 0402")
    (tags "resistor SMD 0402")
    (property "Author" "Antmicro")
    (property "License" "Apache-2.0")
    (property "MPN" "CR0402-FX-1402GLF")
    (property "Manufacturer" "Bourns")
    (property "Sheetfile" "tb.kicad_sch")
    (property "Sheetname" "TB Controller")
    (property "Tolerance" "1%")
    (property "Val" "14k")
    (property "dnp" "")
    (property "ki_description" "SMD Chip Resistor, 14 kohm, ± 1%, 100 mW, 0402 [1005 Metric], Thick Film, Precision")
    (property "ki_keywords" "0402, SMT, RESISTOR, PASSIVE")
    (attr smd)
    (fp_text reference "R63" (at 17.509 7.431 180) (layer "B.SilkS")
        (effects (font (size 0.7 0.7) (thickness 0.15)) (justify left bottom mirror))
    )
    (fp_text value "R_14k_0402" (at -1.011843 -1.772047 180) (layer "B.Fab")
        (effects (font (size 0.7 0.7) (thickness 0.15)) (justify left bottom mirror))
    )
    (fp_text user "Author: Antmicro" (at -0.95 -4.169 180) (layer "B.Fab") hide
        (effects (font (size 0.7 0.7) (thickness 0.15)) (justify left bottom mirror))
    )
    (fp_text user "${REFERENCE}" (at -0.95 -3.168 180) (layer "B.Fab") hide
        (effects (font (size 0.7 0.7) (thickness 0.15)) (justify left bottom mirror))
    )
    (fp_text user "License: Apache-2.0" (at -0.95 -5.169 180) (layer "B.Fab") hide
        (effects (font (size 0.7 0.7) (thickness 0.15)) (justify left bottom mirror))
    )
    (fp_rect (start -0.925 0.47) (end 0.925 -0.47)
      (stroke (width 0.05) (type default)) (fill none) (layer "B.CrtYd"))
    (fp_rect (start -0.5 0.25) (end 0.5 -0.25)
      (stroke (width 0.15) (type solid)) (fill none) (layer "B.Fab"))
    (pad "1" smd roundrect (at -0.48 0) (size 0.59 0.64) (layers "B.Cu" "B.Paste" "B.Mask") (roundrect_rratio 0.25)
      (net 1 "GND") (pintype "passive"))
    (pad "2" smd roundrect (at 0.48 0) (size 0.59 0.64) (layers "B.Cu" "B.Paste" "B.Mask") (roundrect_rratio 0.25)
      (net 177 "Net-(U4C-DPSNK_RBIAS)") (pintype "passive"))
  )
	(footprint "antmicro-footprints:C_0402_1005Metric" (layer "B.Cu")
    (at 161 76.928922)
    (descr "Capacitor SMD 0402")
    (tags "capacitor SMD 0402")
    (property "Author" "Antmicro")
    (property "Dielectric" "X5R")
    (property "License" "Apache-2.0")
    (property "MPN" "GRM155R61H104KE14D")
    (property "Manufacturer" "Murata")
    (property "Sheetfile" "connectors.kicad_sch")
    (property "Sheetname" "Connectors")
    (property "Val" "100n")
    (property "Voltage" "50V")
    (property "ki_description" "SMD Multilayer Ceramic Capacitor, 0.1 µF, 50 V, 0402 [1005 Metric], ± 10%, X5R, GRM Series")
    (property "ki_keywords" "0402, SMT, CAPACITOR, PASSIVE, CERAMIC, MLCC")
    (attr smd)
    (fp_text reference "C3" (at -0.98 0.509078 180) (layer "B.SilkS")
        (effects (font (size 0.7 0.7) (thickness 0.15)) (justify left bottom mirror))
    )
    (fp_text value "C_100n_0402" (at -1.022927 -2.155213 180) (layer "B.Fab")
        (effects (font (size 0.7 0.7) (thickness 0.15)) (justify left bottom mirror))
    )
    (fp_text user "${REFERENCE}" (at -0.939 -4.599 180) (layer "B.Fab") hide
        (effects (font (size 0.7 0.7) (thickness 0.15)) (justify left bottom mirror))
    )
    (fp_text user "Author: Antmicro" (at -0.939 -3.399 180) (layer "B.Fab") hide
        (effects (font (size 0.7 0.7) (thickness 0.15)) (justify left bottom mirror))
    )
    (fp_text user "License: Apache-2.0" (at -0.939 -5.799 180) (layer "B.Fab") hide
        (effects (font (size 0.7 0.7) (thickness 0.15)) (justify left bottom mirror))
    )
    (fp_rect (start -0.925 0.47) (end 0.925 -0.47)
      (stroke (width 0.05) (type default)) (fill none) (layer "B.CrtYd"))
    (fp_line (start -0.494 -0.248) (end -0.494 0.25)
      (stroke (width 0.15) (type solid)) (layer "B.Fab"))
    (fp_line (start -0.494 0.25) (end 0.504 0.25)
      (stroke (width 0.15) (type solid)) (layer "B.Fab"))
    (fp_line (start 0.504 -0.248) (end -0.494 -0.248)
      (stroke (width 0.15) (type solid)) (layer "B.Fab"))
    (fp_line (start 0.504 0.25) (end 0.504 -0.248)
      (stroke (width 0.15) (type solid)) (layer "B.Fab"))
    (pad "1" smd roundrect (at -0.48 0) (size 0.59 0.64) (layers "B.Cu" "B.Paste" "B.Mask") (roundrect_rratio 0.25)
      (net 1 "GND") (pintype "passive"))
    (pad "2" smd roundrect (at 0.48 0) (size 0.59 0.64) (layers "B.Cu" "B.Paste" "B.Mask") (roundrect_rratio 0.25)
      (net 3 "5V0_USB") (pintype "passive"))
  )
)
